# S9S_MB_2U (Grand Teton) — schematic netlist excerpt (pin names and nets, part order shuffled) for the footprints in the layout excerpt that follows; sources: Cadence DE-HDL packaged netlist, KiCad conversion of 03242023_DA0F0TMBIJ0_F0T_Motherboard_J_brd_V01_OCP.brd

R3197  Q_RES  22 1% CHIP  pkg 0402LF  page 207 : A = CLK_100M_OCP_V3_2_B_R_DN ; B = CLK_100M_OCP_V3_2_B_DN
R4577  Q_RES  0 5% EMPTY  pkg 0402LF  page 146 : A = GPU_3V3IO_RSVD3_FFU ; B = GPU_3V3IO_RSVD3_FFU_ISO

(kicad_pcb
	(version 20260206)
	(generator "pcbnew")
	(generator_version "10.0")
	(general
		(thickness 1.6)
		(legacy_teardrops no)
	)
	(paper "A4")
	(title_block
		(title "03242023_DA0F0TMBIJ0_F0T_Motherboard_J_brd_V01_OCP.brd")
		(comment 1 "Grand Teton / footprints 422-423 of 6105")
	)
	(layers
		(0 "F.Cu" signal "TOP")
		(4 "In1.Cu" signal "GND")
		(6 "In2.Cu" signal "IN1")
		(8 "In3.Cu" signal "GND1")
		(10 "In4.Cu" signal "IN2")
		(12 "In5.Cu" signal "GND2")
		(14 "In6.Cu" signal "IN3")
		(16 "In7.Cu" signal "GND3")
		(18 "In8.Cu" signal "VCC")
		(20 "In9.Cu" signal "VCC1")
		(22 "In10.Cu" signal "GND4")
		(24 "In11.Cu" signal "IN4")
		(26 "In12.Cu" signal "GND5")
		(28 "In13.Cu" signal "IN5")
		(30 "In14.Cu" signal "GND6")
		(32 "In15.Cu" signal "IN6")
		(34 "In16.Cu" signal "GND7")
		(2 "B.Cu" signal "BOTTOM")
		(9 "F.Adhes" user "F.Adhesive")
		(11 "B.Adhes" user "B.Adhesive")
		(13 "F.Paste" user "Package Geometry/Pastemask Top")
		(15 "B.Paste" user "Package Geometry/Pastemask Bottom")
		(5 "F.SilkS" user "Ref Des/Silkscreen Top")
		(7 "B.SilkS" user "Ref Des/Silkscreen Bottom")
		(1 "F.Mask" user "Board Geometry/Soldermask Top")
		(3 "B.Mask" user "Board Geometry/Soldermask Bottom")
		(17 "Dwgs.User" user "User.Drawings")
		(19 "Cmts.User" user "User.Comments")
		(21 "Eco1.User" user "User.Eco1")
		(23 "Eco2.User" user "User.Eco2")
		(25 "Edge.Cuts" user "Board Geometry/Outline")
		(27 "Margin" user)
		(31 "F.CrtYd" user "Package Geometry/Place Bound Top")
		(29 "B.CrtYd" user "Package Geometry/Place Bound Bottom")
		(35 "F.Fab" user "Ref Des/Assembly Top")
		(33 "B.Fab" user "Ref Des/Assembly Bottom")
	)
	(footprint ""
		(layer "F.Cu")
		(at 303.48809 -428.85106)
		(property "Reference" "R4577"
			(at 0 0 0)
			(layer "F.SilkS")
			(hide yes)
			(effects
				(font
					(size 1.27 1.27)
				)
			)
		)
		(property "Value" ""
			(at 0 0 0)
			(layer "F.Fab")
			(effects
				(font
					(size 1.27 1.27)
				)
			)
		)
		(duplicate_pad_numbers_are_jumpers no)
		(fp_line
			(start -0.7874 -0.4064)
			(end 0.7874 -0.4064)
			(stroke
				(width 0.1524)
				(type default)
			)
			(layer "F.SilkS")
		)
		(fp_line
			(start -0.7874 0.4064)
			(end -0.7874 -0.4064)
			(stroke
				(width 0.1524)
				(type default)
			)
			(layer "F.SilkS")
		)
		(fp_line
			(start 0.7874 -0.4064)
			(end 0.7874 0.4064)
			(stroke
				(width 0.1524)
				(type default)
			)
			(layer "F.SilkS")
		)
		(fp_line
			(start 0.7874 0.4064)
			(end -0.7874 0.4064)
			(stroke
				(width 0.1524)
				(type default)
			)
			(layer "F.SilkS")
		)
		(fp_line
			(start -0.67945 -0.305054)
			(end -0.12065 -0.305054)
			(stroke
				(width 0.1)
				(type default)
			)
			(layer "F.Fab")
		)
		(fp_line
			(start -0.67945 0.3048)
			(end -0.67945 -0.305054)
			(stroke
				(width 0.1)
				(type default)
			)
			(layer "F.Fab")
		)
		(fp_line
			(start -0.12065 -0.305054)
			(end -0.12065 -0.2794)
			(stroke
				(width 0.1)
				(type default)
			)
			(layer "F.Fab")
		)
		(fp_line
			(start -0.12065 -0.2794)
			(end 0.12065 -0.2794)
			(stroke
				(width 0.1)
				(type default)
			)
			(layer "F.Fab")
		)
		(fp_line
			(start -0.12065 0.2794)
			(end -0.12065 0.3048)
			(stroke
				(width 0.1)
				(type default)
			)
			(layer "F.Fab")
		)
		(fp_line
			(start -0.12065 0.3048)
			(end -0.67945 0.3048)
			(stroke
				(width 0.1)
				(type default)
			)
			(layer "F.Fab")
		)
		(fp_line
			(start 0.120396 0.2794)
			(end -0.12065 0.2794)
			(stroke
				(width 0.1)
				(type default)
			)
			(layer "F.Fab")
		)
		(fp_line
			(start 0.120396 0.3048)
			(end 0.120396 0.2794)
			(stroke
				(width 0.1)
				(type default)
			)
			(layer "F.Fab")
		)
		(fp_line
			(start 0.12065 -0.3048)
			(end 0.67945 -0.3048)
			(stroke
				(width 0.1)
				(type default)
			)
			(layer "F.Fab")
		)
		(fp_line
			(start 0.12065 -0.2794)
			(end 0.12065 -0.3048)
			(stroke
				(width 0.1)
				(type default)
			)
			(layer "F.Fab")
		)
		(fp_line
			(start 0.67945 -0.3048)
			(end 0.67945 0.3048)
			(stroke
				(width 0.1)
				(type default)
			)
			(layer "F.Fab")
		)
		(fp_line
			(start 0.67945 0.3048)
			(end 0.120396 0.3048)
			(stroke
				(width 0.1)
				(type default)
			)
			(layer "F.Fab")
		)
		(pad "1" smd circle
			(at -0.40005 0)
			(size 0 0)
			(layers "F.Cu" "F.Mask" "F.Paste")
			(net "GPU_3V3IO_RSVD3_FFU")
		)
		(pad "2" smd circle
			(at 0.40005 0)
			(size 0 0)
			(layers "F.Cu" "F.Mask" "F.Paste")
			(net "GPU_3V3IO_RSVD3_FFU_ISO")
		)
	)
	(footprint ""
		(layer "F.Cu")
		(at 238.187738 -119.183658 -90)
		(property "Reference" "R3197"
			(at 0 0 270)
			(layer "F.SilkS")
			(hide yes)
			(effects
				(font
					(size 1.27 1.27)
				)
			)
		)
		(property "Value" ""
			(at 0 0 270)
			(layer "F.Fab")
			(effects
				(font
					(size 1.27 1.27)
				)
			)
		)
		(duplicate_pad_numbers_are_jumpers no)
		(fp_line
			(start 0.438658 0.4064)
			(end -0.287782 0.4064)
			(stroke
				(width 0.1524)
				(type default)
			)
			(layer "F.SilkS")
		)
		(fp_line
			(start -0.7874 0.121158)
			(end -0.7874 -0.4064)
			(stroke
				(width 0.1524)
				(type default)
			)
			(layer "F.SilkS")
		)
		(fp_line
			(start -0.7874 -0.4064)
			(end 0.7874 -0.4064)
			(stroke
				(width 0.1524)
				(type default)
			)
			(layer "F.SilkS")
		)
		(fp_line
			(start 0.7874 -0.4064)
			(end 0.7874 0.055118)
			(stroke
				(width 0.1524)
				(type default)
			)
			(layer "F.SilkS")
		)
		(fp_line
			(start -0.67945 0.3048)
			(end -0.67945 -0.305054)
			(stroke
				(width 0.1)
				(type default)
			)
			(layer "F.Fab")
		)
		(fp_line
			(start -0.12065 0.3048)
			(end -0.67945 0.3048)
			(stroke
				(width 0.1)
				(type default)
			)
			(layer "F.Fab")
		)
		(fp_line
			(start 0.120396 0.3048)
			(end 0.120396 0.2794)
			(stroke
				(width 0.1)
				(type default)
			)
			(layer "F.Fab")
		)
		(fp_line
			(start 0.67945 0.3048)
			(end 0.120396 0.3048)
			(stroke
				(width 0.1)
				(type default)
			)
			(layer "F.Fab")
		)
		(fp_line
			(start -0.12065 0.2794)
			(end -0.12065 0.3048)
			(stroke
				(width 0.1)
				(type default)
			)
			(layer "F.Fab")
		)
		(fp_line
			(start 0.120396 0.2794)
			(end -0.12065 0.2794)
			(stroke
				(width 0.1)
				(type default)
			)
			(layer "F.Fab")
		)
		(fp_line
			(start -0.12065 -0.2794)
			(end 0.12065 -0.2794)
			(stroke
				(width 0.1)
				(type default)
			)
			(layer "F.Fab")
		)
		(fp_line
			(start 0.12065 -0.2794)
			(end 0.12065 -0.3048)
			(stroke
				(width 0.1)
				(type default)
			)
			(layer "F.Fab")
		)
		(fp_line
			(start 0.12065 -0.3048)
			(end 0.67945 -0.3048)
			(stroke
				(width 0.1)
				(type default)
			)
			(layer "F.Fab")
		)
		(fp_line
			(start 0.67945 -0.3048)
			(end 0.67945 0.3048)
			(stroke
				(width 0.1)
				(type default)
			)
			(layer "F.Fab")
		)
		(fp_line
			(start -0.67945 -0.305054)
			(end -0.12065 -0.305054)
			(stroke
				(width 0.1)
				(type default)
			)
			(layer "F.Fab")
		)
		(fp_line
			(start -0.12065 -0.305054)
			(end -0.12065 -0.2794)
			(stroke
				(width 0.1)
				(type default)
			)
			(layer "F.Fab")
		)
		(pad "1" smd circle
			(at -0.40005 0 270)
			(size 0 0)
			(layers "F.Cu" "F.Mask" "F.Paste")
			(net "CLK_100M_OCP_V3_2_B_R_DN")
		)
		(pad "2" smd circle
			(at 0.40005 0 270)
			(size 0 0)
			(layers "F.Cu" "F.Mask" "F.Paste")
			(net "CLK_100M_OCP_V3_2_B_DN")
		)
	)
)
